(kicad_pcb
	(version 20260206)
	(generator "pcbnew")
	(generator_version "10.0")
	(general
		(thickness 1.6)
		(legacy_teardrops no)
	)
	(paper "A4")
	(title_block
		(title "04192023_DAF0TMB3IC0_F0TG_MB_C_brd_V02_OCP.brd")
		(comment 1 "Grand Teton / footprints 1568-1574 of 8354")
	)
	(layers
		(0 "F.Cu" signal "TOP")
		(4 "In1.Cu" signal "GND")
		(6 "In2.Cu" signal "IN1")
		(8 "In3.Cu" signal "GND1")
		(10 "In4.Cu" signal "IN2")
		(12 "In5.Cu" signal "GND2")
		(14 "In6.Cu" signal "IN3")
		(16 "In7.Cu" signal "GND3")
		(18 "In8.Cu" signal "VCC")
		(20 "In9.Cu" signal "VCC1")
		(22 "In10.Cu" signal "GND4")
		(24 "In11.Cu" signal "IN4")
		(26 "In12.Cu" signal "GND5")
		(28 "In13.Cu" signal "IN5")
		(30 "In14.Cu" signal "GND6")
		(32 "In15.Cu" signal "IN6")
		(34 "In16.Cu" signal "GND7")
		(2 "B.Cu" signal "BOTTOM")
		(9 "F.Adhes" user "F.Adhesive")
		(11 "B.Adhes" user "B.Adhesive")
		(13 "F.Paste" user "Package Geometry/Pastemask Top")
		(15 "B.Paste" user "Package Geometry/Pastemask Bottom")
		(5 "F.SilkS" user "Ref Des/Silkscreen Top")
		(7 "B.SilkS" user "Ref Des/Silkscreen Bottom")
		(1 "F.Mask" user "Board Geometry/Soldermask Top")
		(3 "B.Mask" user "Board Geometry/Soldermask Bottom")
		(17 "Dwgs.User" user "User.Drawings")
		(19 "Cmts.User" user "User.Comments")
		(21 "Eco1.User" user "User.Eco1")
		(23 "Eco2.User" user "User.Eco2")
		(25 "Edge.Cuts" user "Board Geometry/Outline")
		(27 "Margin" user)
		(31 "F.CrtYd" user "Package Geometry/Place Bound Top")
		(29 "B.CrtYd" user "Package Geometry/Place Bound Bottom")
		(35 "F.Fab" user "Ref Des/Assembly Top")
		(33 "B.Fab" user "Ref Des/Assembly Bottom")
	)
	(footprint ""
		(layer "F.Cu")
		(at 47.18304 -434.057552 90)
		(property "Reference" "R3317"
			(at 0 0 90)
			(layer "F.SilkS")
			(hide yes)
			(effects
				(font
					(size 1.27 1.27)
				)
			)
		)
		(property "Value" ""
			(at 0 0 90)
			(layer "F.Fab")
			(effects
				(font
					(size 1.27 1.27)
				)
			)
		)
		(duplicate_pad_numbers_are_jumpers no)
		(fp_line
			(start 0.7874 -0.4064)
			(end 0.7874 0.4064)
			(stroke
				(width 0.1524)
				(type default)
			)
			(layer "F.SilkS")
		)
		(fp_line
			(start -0.7874 -0.4064)
			(end 0.7874 -0.4064)
			(stroke
				(width 0.1524)
				(type default)
			)
			(layer "F.SilkS")
		)
		(fp_line
			(start 0.7874 0.4064)
			(end -0.7874 0.4064)
			(stroke
				(width 0.1524)
				(type default)
			)
			(layer "F.SilkS")
		)
		(fp_line
			(start -0.7874 0.4064)
			(end -0.7874 -0.4064)
			(stroke
				(width 0.1524)
				(type default)
			)
			(layer "F.SilkS")
		)
		(fp_line
			(start -0.12065 -0.305054)
			(end -0.12065 -0.2794)
			(stroke
				(width 0.1)
				(type default)
			)
			(layer "F.Fab")
		)
		(fp_line
			(start -0.67945 -0.305054)
			(end -0.12065 -0.305054)
			(stroke
				(width 0.1)
				(type default)
			)
			(layer "F.Fab")
		)
		(fp_line
			(start 0.67945 -0.3048)
			(end 0.67945 0.3048)
			(stroke
				(width 0.1)
				(type default)
			)
			(layer "F.Fab")
		)
		(fp_line
			(start 0.12065 -0.3048)
			(end 0.67945 -0.3048)
			(stroke
				(width 0.1)
				(type default)
			)
			(layer "F.Fab")
		)
		(fp_line
			(start 0.12065 -0.2794)
			(end 0.12065 -0.3048)
			(stroke
				(width 0.1)
				(type default)
			)
			(layer "F.Fab")
		)
		(fp_line
			(start -0.12065 -0.2794)
			(end 0.12065 -0.2794)
			(stroke
				(width 0.1)
				(type default)
			)
			(layer "F.Fab")
		)
		(fp_line
			(start 0.120396 0.2794)
			(end -0.12065 0.2794)
			(stroke
				(width 0.1)
				(type default)
			)
			(layer "F.Fab")
		)
		(fp_line
			(start -0.12065 0.2794)
			(end -0.12065 0.3048)
			(stroke
				(width 0.1)
				(type default)
			)
			(layer "F.Fab")
		)
		(fp_line
			(start 0.67945 0.3048)
			(end 0.120396 0.3048)
			(stroke
				(width 0.1)
				(type default)
			)
			(layer "F.Fab")
		)
		(fp_line
			(start 0.120396 0.3048)
			(end 0.120396 0.2794)
			(stroke
				(width 0.1)
				(type default)
			)
			(layer "F.Fab")
		)
		(fp_line
			(start -0.12065 0.3048)
			(end -0.67945 0.3048)
			(stroke
				(width 0.1)
				(type default)
			)
			(layer "F.Fab")
		)
		(fp_line
			(start -0.67945 0.3048)
			(end -0.67945 -0.305054)
			(stroke
				(width 0.1)
				(type default)
			)
			(layer "F.Fab")
		)
		(pad "1" smd circle
			(at -0.40005 0 90)
			(size 0 0)
			(layers "F.Cu" "F.Mask" "F.Paste")
			(net "P3V3_AUX")
		)
		(pad "2" smd circle
			(at 0.40005 0 90)
			(size 0 0)
			(layers "F.Cu" "F.Mask" "F.Paste")
			(net "GPU_FPGA_RST_R1_BUF_N")
		)
	)
	(footprint ""
		(layer "F.Cu")
		(at 325.9074 -363.22)
		(property "Reference" "R352"
			(at 0 0 0)
			(layer "F.SilkS")
			(hide yes)
			(effects
				(font
					(size 1.27 1.27)
				)
			)
		)
		(property "Value" ""
			(at 0 0 0)
			(layer "F.Fab")
			(effects
				(font
					(size 1.27 1.27)
				)
			)
		)
		(duplicate_pad_numbers_are_jumpers no)
		(fp_line
			(start -0.7874 -0.4064)
			(end 0.7874 -0.4064)
			(stroke
				(width 0.1524)
				(type default)
			)
			(layer "F.SilkS")
		)
		(fp_line
			(start -0.7874 0.4064)
			(end -0.7874 -0.4064)
			(stroke
				(width 0.1524)
				(type default)
			)
			(layer "F.SilkS")
		)
		(fp_line
			(start 0.7874 -0.4064)
			(end 0.7874 0.4064)
			(stroke
				(width 0.1524)
				(type default)
			)
			(layer "F.SilkS")
		)
		(fp_line
			(start 0.7874 0.4064)
			(end -0.7874 0.4064)
			(stroke
				(width 0.1524)
				(type default)
			)
			(layer "F.SilkS")
		)
		(fp_line
			(start -0.67945 -0.305054)
			(end -0.12065 -0.305054)
			(stroke
				(width 0.1)
				(type default)
			)
			(layer "F.Fab")
		)
		(fp_line
			(start -0.67945 0.3048)
			(end -0.67945 -0.305054)
			(stroke
				(width 0.1)
				(type default)
			)
			(layer "F.Fab")
		)
		(fp_line
			(start -0.12065 -0.305054)
			(end -0.12065 -0.2794)
			(stroke
				(width 0.1)
				(type default)
			)
			(layer "F.Fab")
		)
		(fp_line
			(start -0.12065 -0.2794)
			(end 0.12065 -0.2794)
			(stroke
				(width 0.1)
				(type default)
			)
			(layer "F.Fab")
		)
		(fp_line
			(start -0.12065 0.2794)
			(end -0.12065 0.3048)
			(stroke
				(width 0.1)
				(type default)
			)
			(layer "F.Fab")
		)
		(fp_line
			(start -0.12065 0.3048)
			(end -0.67945 0.3048)
			(stroke
				(width 0.1)
				(type default)
			)
			(layer "F.Fab")
		)
		(fp_line
			(start 0.120396 0.2794)
			(end -0.12065 0.2794)
			(stroke
				(width 0.1)
				(type default)
			)
			(layer "F.Fab")
		)
		(fp_line
			(start 0.120396 0.3048)
			(end 0.120396 0.2794)
			(stroke
				(width 0.1)
				(type default)
			)
			(layer "F.Fab")
		)
		(fp_line
			(start 0.12065 -0.3048)
			(end 0.67945 -0.3048)
			(stroke
				(width 0.1)
				(type default)
			)
			(layer "F.Fab")
		)
		(fp_line
			(start 0.12065 -0.2794)
			(end 0.12065 -0.3048)
			(stroke
				(width 0.1)
				(type default)
			)
			(layer "F.Fab")
		)
		(fp_line
			(start 0.67945 -0.3048)
			(end 0.67945 0.3048)
			(stroke
				(width 0.1)
				(type default)
			)
			(layer "F.Fab")
		)
		(fp_line
			(start 0.67945 0.3048)
			(end 0.120396 0.3048)
			(stroke
				(width 0.1)
				(type default)
			)
			(layer "F.Fab")
		)
		(pad "1" smd circle
			(at -0.40005 0)
			(size 0 0)
			(layers "F.Cu" "F.Mask" "F.Paste")
			(net "SMB_SCM_2_R5_SDA")
		)
		(pad "2" smd circle
			(at 0.40005 0)
			(size 0 0)
			(layers "F.Cu" "F.Mask" "F.Paste")
			(net "SMB_SCM_2_R6_SDA")
		)
	)
	(footprint ""
		(layer "F.Cu")
		(at 111.13897 -175.506634 -90)
		(property "Reference" "PC287"
			(at 0 0 270)
			(layer "F.SilkS")
			(hide yes)
			(effects
				(font
					(size 1.27 1.27)
				)
			)
		)
		(property "Value" ""
			(at 0 0 270)
			(layer "F.Fab")
			(effects
				(font
					(size 1.27 1.27)
				)
			)
		)
		(duplicate_pad_numbers_are_jumpers no)
		(fp_line
			(start -0.7874 0.4064)
			(end -0.7874 -0.4064)
			(stroke
				(width 0.1524)
				(type default)
			)
			(layer "F.SilkS")
		)
		(fp_line
			(start -0.362966 0.4064)
			(end -0.7874 0.4064)
			(stroke
				(width 0.1524)
				(type default)
			)
			(layer "F.SilkS")
		)
		(fp_line
			(start 0.7874 0.4064)
			(end 0.373634 0.4064)
			(stroke
				(width 0.1524)
				(type default)
			)
			(layer "F.SilkS")
		)
		(fp_line
			(start -0.7874 -0.4064)
			(end 0.7874 -0.4064)
			(stroke
				(width 0.1524)
				(type default)
			)
			(layer "F.SilkS")
		)
		(fp_line
			(start 0.7874 -0.4064)
			(end 0.7874 0.4064)
			(stroke
				(width 0.1524)
				(type default)
			)
			(layer "F.SilkS")
		)
		(fp_line
			(start -0.67945 0.3048)
			(end -0.67945 -0.305054)
			(stroke
				(width 0.1)
				(type default)
			)
			(layer "F.Fab")
		)
		(fp_line
			(start -0.12065 0.3048)
			(end -0.67945 0.3048)
			(stroke
				(width 0.1)
				(type default)
			)
			(layer "F.Fab")
		)
		(fp_line
			(start 0.120396 0.3048)
			(end 0.120396 0.2794)
			(stroke
				(width 0.1)
				(type default)
			)
			(layer "F.Fab")
		)
		(fp_line
			(start 0.67945 0.3048)
			(end 0.120396 0.3048)
			(stroke
				(width 0.1)
				(type default)
			)
			(layer "F.Fab")
		)
		(fp_line
			(start -0.12065 0.2794)
			(end -0.12065 0.3048)
			(stroke
				(width 0.1)
				(type default)
			)
			(layer "F.Fab")
		)
		(fp_line
			(start 0.120396 0.2794)
			(end -0.12065 0.2794)
			(stroke
				(width 0.1)
				(type default)
			)
			(layer "F.Fab")
		)
		(fp_line
			(start -0.12065 -0.2794)
			(end 0.12065 -0.2794)
			(stroke
				(width 0.1)
				(type default)
			)
			(layer "F.Fab")
		)
		(fp_line
			(start 0.12065 -0.2794)
			(end 0.12065 -0.3048)
			(stroke
				(width 0.1)
				(type default)
			)
			(layer "F.Fab")
		)
		(fp_line
			(start 0.12065 -0.3048)
			(end 0.67945 -0.3048)
			(stroke
				(width 0.1)
				(type default)
			)
			(layer "F.Fab")
		)
		(fp_line
			(start 0.67945 -0.3048)
			(end 0.67945 0.3048)
			(stroke
				(width 0.1)
				(type default)
			)
			(layer "F.Fab")
		)
		(fp_line
			(start -0.67945 -0.305054)
			(end -0.12065 -0.305054)
			(stroke
				(width 0.1)
				(type default)
			)
			(layer "F.Fab")
		)
		(fp_line
			(start -0.12065 -0.305054)
			(end -0.12065 -0.2794)
			(stroke
				(width 0.1)
				(type default)
			)
			(layer "F.Fab")
		)
		(pad "1" smd circle
			(at -0.40005 0 270)
			(size 0 0)
			(layers "F.Cu" "F.Mask" "F.Paste")
			(net "PVDDCR_CPU0_P1_VCC4")
		)
		(pad "2" smd circle
			(at 0.40005 0 270)
			(size 0 0)
			(layers "F.Cu" "F.Mask" "F.Paste")
			(net "GND")
		)
	)
	(footprint ""
		(layer "F.Cu")
		(at 88.344502 -375.49963 -90)
		(property "Reference" "C726"
			(at 0 0 270)
			(layer "F.SilkS")
			(hide yes)
			(effects
				(font
					(size 1.27 1.27)
				)
			)
		)
		(property "Value" ""
			(at 0 0 270)
			(layer "F.Fab")
			(effects
				(font
					(size 1.27 1.27)
				)
			)
		)
		(duplicate_pad_numbers_are_jumpers no)
		(fp_line
			(start -0.299974 0.150114)
			(end -0.299974 -0.150114)
			(stroke
				(width 0.1)
				(type default)
			)
			(layer "F.Fab")
		)
		(fp_line
			(start 0.299974 0.150114)
			(end -0.299974 0.150114)
			(stroke
				(width 0.1)
				(type default)
			)
			(layer "F.Fab")
		)
		(fp_line
			(start -0.299974 -0.150114)
			(end 0.299974 -0.150114)
			(stroke
				(width 0.1)
				(type default)
			)
			(layer "F.Fab")
		)
		(fp_line
			(start 0.299974 -0.150114)
			(end 0.299974 0.150114)
			(stroke
				(width 0.1)
				(type default)
			)
			(layer "F.Fab")
		)
		(pad "1" smd rect
			(at -0.2667 0 270)
			(size 0.3048 0.381)
			(layers "F.Cu" "F.Mask" "F.Paste")
			(net "P5E_CPU1_P1_TX_C_DN<7>")
		)
		(pad "2" smd rect
			(at 0.2667 0 270)
			(size 0.3048 0.381)
			(layers "F.Cu" "F.Mask" "F.Paste")
			(net "P5E_CPU1_P1_TX_DN<7>")
		)
	)
	(footprint ""
		(layer "F.Cu")
		(at 150.47722 -65.387474)
		(property "Reference" "Q62"
			(at -1.4224 -2.327148 0)
			(unlocked yes)
			(layer "F.SilkS")
			(effects
				(font
					(size 0.7874 0.5842)
					(thickness 0.1524)
				)
			)
		)
		(property "Value" ""
			(at 0 0 0)
			(layer "F.Fab")
			(effects
				(font
					(size 1.27 1.27)
				)
			)
		)
		(duplicate_pad_numbers_are_jumpers no)
		(fp_line
			(start -1.949958 -1.610106)
			(end 1.949958 -1.610106)
			(stroke
				(width 0.1524)
				(type default)
			)
			(layer "F.SilkS")
		)
		(fp_line
			(start -1.949958 1.610106)
			(end -1.949958 -1.610106)
			(stroke
				(width 0.1524)
				(type default)
			)
			(layer "F.SilkS")
		)
		(fp_line
			(start 1.949958 -1.560068)
			(end 1.949958 1.610106)
			(stroke
				(width 0.1524)
				(type default)
			)
			(layer "F.SilkS")
		)
		(fp_line
			(start 1.949958 1.610106)
			(end -1.949958 1.610106)
			(stroke
				(width 0.1524)
				(type default)
			)
			(layer "F.SilkS")
		)
		(fp_line
			(start -0.750062 -1.560068)
			(end 0.750062 -1.560068)
			(stroke
				(width 0.1)
				(type default)
			)
			(layer "F.Fab")
		)
		(fp_line
			(start -0.750062 1.560068)
			(end -0.750062 -1.560068)
			(stroke
				(width 0.1)
				(type default)
			)
			(layer "F.Fab")
		)
		(fp_line
			(start 0.750062 -1.560068)
			(end 0.750062 1.560068)
			(stroke
				(width 0.1)
				(type default)
			)
			(layer "F.Fab")
		)
		(fp_line
			(start 0.750062 1.560068)
			(end -0.750062 1.560068)
			(stroke
				(width 0.1)
				(type default)
			)
			(layer "F.Fab")
		)
		(pad "D" smd rect
			(at 1.100074 0 270)
			(size 1.016 1.4224)
			(layers "F.Cu" "F.Mask" "F.Paste")
			(net "JTAG_BMC_OE_N")
		)
		(pad "G" smd rect
			(at -1.100074 -0.94996 270)
			(size 1.016 1.4224)
			(layers "F.Cu" "F.Mask" "F.Paste")
			(net "JTAG_BMC_OE")
		)
		(pad "S" smd rect
			(at -1.100074 0.94996 270)
			(size 1.016 1.4224)
			(layers "F.Cu" "F.Mask" "F.Paste")
			(net "GND")
		)
	)
	(footprint ""
		(layer "F.Cu")
		(at 306.002182 -351.573846 90)
		(property "Reference" "PC113_4"
			(at 0 0 90)
			(layer "F.SilkS")
			(hide yes)
			(effects
				(font
					(size 1.27 1.27)
				)
			)
		)
		(property "Value" ""
			(at 0 0 90)
			(layer "F.Fab")
			(effects
				(font
					(size 1.27 1.27)
				)
			)
		)
		(duplicate_pad_numbers_are_jumpers no)
		(fp_line
			(start 0.7874 -0.4064)
			(end 0.7874 0.4064)
			(stroke
				(width 0.1524)
				(type default)
			)
			(layer "F.SilkS")
		)
		(fp_line
			(start -0.7874 -0.4064)
			(end 0.7874 -0.4064)
			(stroke
				(width 0.1524)
				(type default)
			)
			(layer "F.SilkS")
		)
		(fp_line
			(start 0.7874 0.4064)
			(end -0.7874 0.4064)
			(stroke
				(width 0.1524)
				(type default)
			)
			(layer "F.SilkS")
		)
		(fp_line
			(start -0.7874 0.4064)
			(end -0.7874 -0.4064)
			(stroke
				(width 0.1524)
				(type default)
			)
			(layer "F.SilkS")
		)
		(fp_line
			(start -0.12065 -0.305054)
			(end -0.12065 -0.2794)
			(stroke
				(width 0.1)
				(type default)
			)
			(layer "F.Fab")
		)
		(fp_line
			(start -0.67945 -0.305054)
			(end -0.12065 -0.305054)
			(stroke
				(width 0.1)
				(type default)
			)
			(layer "F.Fab")
		)
		(fp_line
			(start 0.67945 -0.3048)
			(end 0.67945 0.3048)
			(stroke
				(width 0.1)
				(type default)
			)
			(layer "F.Fab")
		)
		(fp_line
			(start 0.12065 -0.3048)
			(end 0.67945 -0.3048)
			(stroke
				(width 0.1)
				(type default)
			)
			(layer "F.Fab")
		)
		(fp_line
			(start 0.12065 -0.2794)
			(end 0.12065 -0.3048)
			(stroke
				(width 0.1)
				(type default)
			)
			(layer "F.Fab")
		)
		(fp_line
			(start -0.12065 -0.2794)
			(end 0.12065 -0.2794)
			(stroke
				(width 0.1)
				(type default)
			)
			(layer "F.Fab")
		)
		(fp_line
			(start 0.120396 0.2794)
			(end -0.12065 0.2794)
			(stroke
				(width 0.1)
				(type default)
			)
			(layer "F.Fab")
		)
		(fp_line
			(start -0.12065 0.2794)
			(end -0.12065 0.3048)
			(stroke
				(width 0.1)
				(type default)
			)
			(layer "F.Fab")
		)
		(fp_line
			(start 0.67945 0.3048)
			(end 0.120396 0.3048)
			(stroke
				(width 0.1)
				(type default)
			)
			(layer "F.Fab")
		)
		(fp_line
			(start 0.120396 0.3048)
			(end 0.120396 0.2794)
			(stroke
				(width 0.1)
				(type default)
			)
			(layer "F.Fab")
		)
		(fp_line
			(start -0.12065 0.3048)
			(end -0.67945 0.3048)
			(stroke
				(width 0.1)
				(type default)
			)
			(layer "F.Fab")
		)
		(fp_line
			(start -0.67945 0.3048)
			(end -0.67945 -0.305054)
			(stroke
				(width 0.1)
				(type default)
			)
			(layer "F.Fab")
		)
		(pad "1" smd circle
			(at -0.40005 0 90)
			(size 0 0)
			(layers "F.Cu" "F.Mask" "F.Paste")
			(net "PVDDCR_CPU1_P0_VCCS")
		)
		(pad "2" smd circle
			(at 0.40005 0 90)
			(size 0 0)
			(layers "F.Cu" "F.Mask" "F.Paste")
			(net "GND")
		)
	)
	(footprint ""
		(layer "F.Cu")
		(at 258.25958 -58.927492 90)
		(property "Reference" "R3975"
			(at 0 0 90)
			(layer "F.SilkS")
			(hide yes)
			(effects
				(font
					(size 1.27 1.27)
				)
			)
		)
		(property "Value" ""
			(at 0 0 90)
			(layer "F.Fab")
			(effects
				(font
					(size 1.27 1.27)
				)
			)
		)
		(duplicate_pad_numbers_are_jumpers no)
		(fp_line
			(start 0.7874 -0.4064)
			(end 0.7874 0.4064)
			(stroke
				(width 0.1524)
				(type default)
			)
			(layer "F.SilkS")
		)
		(fp_line
			(start -0.7874 -0.4064)
			(end 0.7874 -0.4064)
			(stroke
				(width 0.1524)
				(type default)
			)
			(layer "F.SilkS")
		)
		(fp_line
			(start 0.7874 0.4064)
			(end -0.7874 0.4064)
			(stroke
				(width 0.1524)
				(type default)
			)
			(layer "F.SilkS")
		)
		(fp_line
			(start -0.7874 0.4064)
			(end -0.7874 -0.4064)
			(stroke
				(width 0.1524)
				(type default)
			)
			(layer "F.SilkS")
		)
		(fp_line
			(start -0.12065 -0.305054)
			(end -0.12065 -0.2794)
			(stroke
				(width 0.1)
				(type default)
			)
			(layer "F.Fab")
		)
		(fp_line
			(start -0.67945 -0.305054)
			(end -0.12065 -0.305054)
			(stroke
				(width 0.1)
				(type default)
			)
			(layer "F.Fab")
		)
		(fp_line
			(start 0.67945 -0.3048)
			(end 0.67945 0.3048)
			(stroke
				(width 0.1)
				(type default)
			)
			(layer "F.Fab")
		)
		(fp_line
			(start 0.12065 -0.3048)
			(end 0.67945 -0.3048)
			(stroke
				(width 0.1)
				(type default)
			)
			(layer "F.Fab")
		)
		(fp_line
			(start 0.12065 -0.2794)
			(end 0.12065 -0.3048)
			(stroke
				(width 0.1)
				(type default)
			)
			(layer "F.Fab")
		)
		(fp_line
			(start -0.12065 -0.2794)
			(end 0.12065 -0.2794)
			(stroke
				(width 0.1)
				(type default)
			)
			(layer "F.Fab")
		)
		(fp_line
			(start 0.120396 0.2794)
			(end -0.12065 0.2794)
			(stroke
				(width 0.1)
				(type default)
			)
			(layer "F.Fab")
		)
		(fp_line
			(start -0.12065 0.2794)
			(end -0.12065 0.3048)
			(stroke
				(width 0.1)
				(type default)
			)
			(layer "F.Fab")
		)
		(fp_line
			(start 0.67945 0.3048)
			(end 0.120396 0.3048)
			(stroke
				(width 0.1)
				(type default)
			)
			(layer "F.Fab")
		)
		(fp_line
			(start 0.120396 0.3048)
			(end 0.120396 0.2794)
			(stroke
				(width 0.1)
				(type default)
			)
			(layer "F.Fab")
		)
		(fp_line
			(start -0.12065 0.3048)
			(end -0.67945 0.3048)
			(stroke
				(width 0.1)
				(type default)
			)
			(layer "F.Fab")
		)
		(fp_line
			(start -0.67945 0.3048)
			(end -0.67945 -0.305054)
			(stroke
				(width 0.1)
				(type default)
			)
			(layer "F.Fab")
		)
		(pad "1" smd rect
			(at -0.40005 0 270)
			(size 0.4572 0.508)
			(layers "F.Cu" "F.Mask" "F.Paste")
			(net "P12V_E1S_SENSE_0")
		)
		(pad "2" smd rect
			(at 0.40005 0 270)
			(size 0.4572 0.508)
			(layers "F.Cu" "F.Mask" "F.Paste")
			(net "P12V_E1S_0_ISENSE_MAM_TIC")
		)
	)
)
